(kicad_sch
	(version 20231120)
	(generator "eeschema")
	(generator_version "8.0")
	(paper "A3")
	(title_block
		(title "Jetson Orin Baseboard")
		(date "2025-03-12")
		(rev "1.3.4")
		(company "Antmicro Ltd")
		(comment 1 "www.antmicro.com")
	)
	(junction
		(at 367.03 228.6)
		(diameter 0)
		(color 0 0 0 0)
	)
	(junction
		(at 367.03 222.25)
		(diameter 0)
		(color 0 0 0 0)
	)
	(junction
		(at 367.03 234.95)
		(diameter 0)
		(color 0 0 0 0)
	)
	(wire
		(pts
			(xy 367.03 228.6) (xy 367.03 234.95)
		)
		(stroke
			(width 0)
			(type default)
		)
	)
	(wire
		(pts
			(xy 367.03 234.95) (xy 368.3 234.95)
		)
		(stroke
			(width 0)
			(type default)
		)
	)
	(wire
		(pts
			(xy 368.3 215.9) (xy 367.03 215.9)
		)
		(stroke
			(width 0)
			(type default)
		)
	)
	(wire
		(pts
			(xy 367.03 228.6) (xy 368.3 228.6)
		)
		(stroke
			(width 0)
			(type default)
		)
	)
	(wire
		(pts
			(xy 367.03 234.95) (xy 367.03 237.49)
		)
		(stroke
			(width 0)
			(type default)
		)
	)
	(wire
		(pts
			(xy 367.03 222.25) (xy 368.3 222.25)
		)
		(stroke
			(width 0)
			(type default)
		)
	)
	(wire
		(pts
			(xy 367.03 215.9) (xy 367.03 222.25)
		)
		(stroke
			(width 0)
			(type default)
		)
	)
	(wire
		(pts
			(xy 367.03 222.25) (xy 367.03 228.6)
		)
		(stroke
			(width 0)
			(type default)
		)
	)
	(text "github.com/antmicro/jetson-orin-baseboard"
		(exclude_from_sim no)
		(at 14.605 31.115 0)
		(effects
			(font
				(size 3 3)
				(thickness 0.4)
				(bold yes)
			)
			(justify left bottom)
		)
	)
	(text "Jetson Orin Baseboard"
		(exclude_from_sim no)
		(at 13.97 24.765 0)
		(effects
			(font
				(size 5 5)
				(thickness 0.4)
				(bold yes)
			)
			(justify left bottom)
		)
	)
	(symbol
		(lib_id "antmicropower:GND")
		(at 367.03 237.49 0)
		(unit 1)
		(exclude_from_sim no)
		(in_bom yes)
		(on_board yes)
		(dnp no)
		(property "Reference" "#PWR01"
			(at 367.03 243.84 0)
			(effects
				(font
					(size 1.27 1.27)
				)
				(justify left bottom)
				(hide yes)
			)
		)
		(property "Value" "GND"
			(at 367.03 241.3 0)
			(effects
				(font
					(size 1.27 1.27)
					(thickness 0.15)
				)
			)
		)
		(property "Footprint" ""
			(at 375.92 245.11 0)
			(effects
				(font
					(size 1.27 1.27)
					(thickness 0.15)
				)
				(justify left bottom)
				(hide yes)
			)
		)
		(property "Datasheet" ""
			(at 375.92 250.19 0)
			(effects
				(font
					(size 1.27 1.27)
					(thickness 0.15)
				)
				(justify left bottom)
				(hide yes)
			)
		)
		(property "Description" ""
			(at 367.03 237.49 0)
			(effects
				(font
					(size 1.27 1.27)
				)
				(hide yes)
			)
		)
		(property "Author" "Antmicro"
			(at 375.92 245.11 0)
			(effects
				(font
					(size 1.27 1.27)
					(thickness 0.15)
				)
				(justify left bottom)
				(hide yes)
			)
		)
		(property "License" "Apache-2.0"
			(at 375.92 247.65 0)
			(effects
				(font
					(size 1.27 1.27)
					(thickness 0.15)
				)
				(justify left bottom)
				(hide yes)
			)
		)
		(pin "1"
		)
		(instances
			(project "jetson-orin-baseboard"
				(path ""
					(reference "#PWR01")
					(unit 1)
				)
			)
		)
	)
	(symbol
		(lib_id "antmicroMechanicalParts:Spacer_Drill3.7mm_H6.5mm_9774065151R")
		(at 368.3 215.9 0)
		(unit 1)
		(exclude_from_sim no)
		(in_bom yes)
		(on_board yes)
		(dnp no)
		(fields_autoplaced yes)
		(property "Reference" "H3"
			(at 377.19 214.63 0)
			(effects
				(font
					(size 1.27 1.27)
					(thickness 0.15)
				)
				(justify left)
			)
		)
		(property "Value" "Spacer_Drill3.7mm_H6.5mm_9774065151R"
			(at 383.54 226.06 0)
			(effects
				(font
					(size 1.27 1.27)
					(thickness 0.15)
				)
				(justify left bottom)
				(hide yes)
			)
		)
		(property "Footprint" "antmicro-footprints:Spacer_Drill3.7mm_H6.5mm_9774065151R"
			(at 383.54 228.6 0)
			(effects
				(font
					(size 1.27 1.27)
					(thickness 0.15)
				)
				(justify left bottom)
				(hide yes)
			)
		)
		(property "Datasheet" "https://www.we-online.com/components/products/datasheet/9774065151R.pdf"
			(at 383.54 231.14 0)
			(effects
				(font
					(size 1.27 1.27)
					(thickness 0.15)
				)
				(justify left bottom)
				(hide yes)
			)
		)
		(property "Description" ""
			(at 368.3 215.9 0)
			(effects
				(font
					(size 1.27 1.27)
				)
				(hide yes)
			)
		)
		(property "Manufacturer" "Würth Elektronik"
			(at 383.54 233.68 0)
			(effects
				(font
					(size 1.27 1.27)
					(thickness 0.15)
				)
				(justify left bottom)
				(hide yes)
			)
		)
		(property "MPN" "9774065151R"
			(at 377.19 217.17 0)
			(effects
				(font
					(size 1.27 1.27)
					(thickness 0.15)
				)
				(justify left)
			)
		)
		(property "Author" "Antmicro"
			(at 383.54 236.22 0)
			(effects
				(font
					(size 1.27 1.27)
					(thickness 0.15)
				)
				(justify left bottom)
				(hide yes)
			)
		)
		(property "License" "Apache-2.0"
			(at 383.54 238.76 0)
			(effects
				(font
					(size 1.27 1.27)
					(thickness 0.15)
				)
				(justify left bottom)
				(hide yes)
			)
		)
		(pin "1"
		)
		(instances
			(project "jetson-orin-baseboard"
				(path ""
					(reference "H3")
					(unit 1)
				)
			)
		)
	)
	(symbol
		(lib_id "antmicroMechanicalParts:Spacer_Drill3.7mm_H6.5mm_9774065151R")
		(at 368.3 228.6 0)
		(unit 1)
		(exclude_from_sim no)
		(in_bom yes)
		(on_board yes)
		(dnp no)
		(fields_autoplaced yes)
		(property "Reference" "H5"
			(at 377.19 227.33 0)
			(effects
				(font
					(size 1.27 1.27)
					(thickness 0.15)
				)
				(justify left)
			)
		)
		(property "Value" "Spacer_Drill3.7mm_H6.5mm_9774065151R"
			(at 383.54 238.76 0)
			(effects
				(font
					(size 1.27 1.27)
					(thickness 0.15)
				)
				(justify left bottom)
				(hide yes)
			)
		)
		(property "Footprint" "antmicro-footprints:Spacer_Drill3.7mm_H6.5mm_9774065151R"
			(at 383.54 241.3 0)
			(effects
				(font
					(size 1.27 1.27)
					(thickness 0.15)
				)
				(justify left bottom)
				(hide yes)
			)
		)
		(property "Datasheet" "https://www.we-online.com/components/products/datasheet/9774065151R.pdf"
			(at 383.54 243.84 0)
			(effects
				(font
					(size 1.27 1.27)
					(thickness 0.15)
				)
				(justify left bottom)
				(hide yes)
			)
		)
		(property "Description" ""
			(at 368.3 228.6 0)
			(effects
				(font
					(size 1.27 1.27)
				)
				(hide yes)
			)
		)
		(property "Manufacturer" "Würth Elektronik"
			(at 383.54 246.38 0)
			(effects
				(font
					(size 1.27 1.27)
					(thickness 0.15)
				)
				(justify left bottom)
				(hide yes)
			)
		)
		(property "MPN" "9774065151R"
			(at 377.19 229.87 0)
			(effects
				(font
					(size 1.27 1.27)
					(thickness 0.15)
				)
				(justify left)
			)
		)
		(property "Author" "Antmicro"
			(at 383.54 248.92 0)
			(effects
				(font
					(size 1.27 1.27)
					(thickness 0.15)
				)
				(justify left bottom)
				(hide yes)
			)
		)
		(property "License" "Apache-2.0"
			(at 383.54 251.46 0)
			(effects
				(font
					(size 1.27 1.27)
					(thickness 0.15)
				)
				(justify left bottom)
				(hide yes)
			)
		)
		(pin "1"
		)
		(instances
			(project "jetson-orin-baseboard"
				(path ""
					(reference "H5")
					(unit 1)
				)
			)
		)
	)
	(symbol
		(lib_id "antmicroMechanicalParts:Spacer_Drill3.7mm_H6.5mm_9774065151R")
		(at 368.3 222.25 0)
		(unit 1)
		(exclude_from_sim no)
		(in_bom yes)
		(on_board yes)
		(dnp no)
		(fields_autoplaced yes)
		(property "Reference" "H4"
			(at 377.19 220.98 0)
			(effects
				(font
					(size 1.27 1.27)
					(thickness 0.15)
				)
				(justify left)
			)
		)
		(property "Value" "Spacer_Drill3.7mm_H6.5mm_9774065151R"
			(at 383.54 232.41 0)
			(effects
				(font
					(size 1.27 1.27)
					(thickness 0.15)
				)
				(justify left bottom)
				(hide yes)
			)
		)
		(property "Footprint" "antmicro-footprints:Spacer_Drill3.7mm_H6.5mm_9774065151R"
			(at 383.54 234.95 0)
			(effects
				(font
					(size 1.27 1.27)
					(thickness 0.15)
				)
				(justify left bottom)
				(hide yes)
			)
		)
		(property "Datasheet" "https://www.we-online.com/components/products/datasheet/9774065151R.pdf"
			(at 383.54 237.49 0)
			(effects
				(font
					(size 1.27 1.27)
					(thickness 0.15)
				)
				(justify left bottom)
				(hide yes)
			)
		)
		(property "Description" ""
			(at 368.3 222.25 0)
			(effects
				(font
					(size 1.27 1.27)
				)
				(hide yes)
			)
		)
		(property "Manufacturer" "Würth Elektronik"
			(at 383.54 240.03 0)
			(effects
				(font
					(size 1.27 1.27)
					(thickness 0.15)
				)
				(justify left bottom)
				(hide yes)
			)
		)
		(property "MPN" "9774065151R"
			(at 377.19 223.52 0)
			(effects
				(font
					(size 1.27 1.27)
					(thickness 0.15)
				)
				(justify left)
			)
		)
		(property "Author" "Antmicro"
			(at 383.54 242.57 0)
			(effects
				(font
					(size 1.27 1.27)
					(thickness 0.15)
				)
				(justify left bottom)
				(hide yes)
			)
		)
		(property "License" "Apache-2.0"
			(at 383.54 245.11 0)
			(effects
				(font
					(size 1.27 1.27)
					(thickness 0.15)
				)
				(justify left bottom)
				(hide yes)
			)
		)
		(pin "1"
		)
		(instances
			(project "jetson-orin-baseboard"
				(path ""
					(reference "H4")
					(unit 1)
				)
			)
		)
	)
	(symbol
		(lib_id "antmicroMechanicalParts:Spacer_Drill3.7mm_H6.5mm_9774065151R")
		(at 368.3 234.95 0)
		(unit 1)
		(exclude_from_sim no)
		(in_bom yes)
		(on_board yes)
		(dnp no)
		(fields_autoplaced yes)
		(property "Reference" "H6"
			(at 377.19 233.68 0)
			(effects
				(font
					(size 1.27 1.27)
					(thickness 0.15)
				)
				(justify left)
			)
		)
		(property "Value" "Spacer_Drill3.7mm_H6.5mm_9774065151R"
			(at 383.54 245.11 0)
			(effects
				(font
					(size 1.27 1.27)
					(thickness 0.15)
				)
				(justify left bottom)
				(hide yes)
			)
		)
		(property "Footprint" "antmicro-footprints:Spacer_Drill3.7mm_H6.5mm_9774065151R"
			(at 383.54 247.65 0)
			(effects
				(font
					(size 1.27 1.27)
					(thickness 0.15)
				)
				(justify left bottom)
				(hide yes)
			)
		)
		(property "Datasheet" "https://www.we-online.com/components/products/datasheet/9774065151R.pdf"
			(at 383.54 250.19 0)
			(effects
				(font
					(size 1.27 1.27)
					(thickness 0.15)
				)
				(justify left bottom)
				(hide yes)
			)
		)
		(property "Description" ""
			(at 368.3 234.95 0)
			(effects
				(font
					(size 1.27 1.27)
				)
				(hide yes)
			)
		)
		(property "Manufacturer" "Würth Elektronik"
			(at 383.54 252.73 0)
			(effects
				(font
					(size 1.27 1.27)
					(thickness 0.15)
				)
				(justify left bottom)
				(hide yes)
			)
		)
		(property "MPN" "9774065151R"
			(at 377.19 236.22 0)
			(effects
				(font
					(size 1.27 1.27)
					(thickness 0.15)
				)
				(justify left)
			)
		)
		(property "Author" "Antmicro"
			(at 383.54 255.27 0)
			(effects
				(font
					(size 1.27 1.27)
					(thickness 0.15)
				)
				(justify left bottom)
				(hide yes)
			)
		)
		(property "License" "Apache-2.0"
			(at 383.54 257.81 0)
			(effects
				(font
					(size 1.27 1.27)
					(thickness 0.15)
				)
				(justify left bottom)
				(hide yes)
			)
		)
		(pin "1"
		)
		(instances
			(project "jetson-orin-baseboard"
				(path ""
					(reference "H6")
					(unit 1)
				)
			)
		)
	)
	(sheet
		(at 203.2 203.2)
		(size 12.7 12.7)
		(fields_autoplaced yes)
		(stroke
			(width 0.1524)
			(type solid)
		)
		(fill
			(color 0 0 0 0.0000)
		)
		(property "Sheetname" "HDMI"
			(at 203.2 202.4884 0)
			(effects
				(font
					(size 1.27 1.27)
				)
				(justify left bottom)
			)
		)
		(property "Sheetfile" "hdmi.kicad_sch"
			(at 203.2 216.4846 0)
			(effects
				(font
					(size 1.27 1.27)
				)
				(justify left top)
			)
		)
		(instances
			(project "jetson-orin-baseboard"
				(path ""
					(page "6")
				)
			)
		)
	)
	(sheet
		(at 171.45 203.2)
		(size 12.7 12.7)
		(fields_autoplaced yes)
		(stroke
			(width 0.1524)
			(type solid)
		)
		(fill
			(color 0 0 0 0.0000)
		)
		(property "Sheetname" "USB3"
			(at 171.45 202.4884 0)
			(effects
				(font
					(size 1.27 1.27)
				)
				(justify left bottom)
			)
		)
		(property "Sheetfile" "usb3.kicad_sch"
			(at 171.45 216.4846 0)
			(effects
				(font
					(size 1.27 1.27)
				)
				(justify left top)
			)
		)
		(instances
			(project "jetson-orin-baseboard"
				(path ""
					(page "5")
				)
			)
		)
	)
	(sheet
		(at 171.45 228.6)
		(size 12.7 12.7)
		(fields_autoplaced yes)
		(stroke
			(width 0.1524)
			(type solid)
		)
		(fill
			(color 0 0 0 0.0000)
		)
		(property "Sheetname" "Supply"
			(at 171.45 227.8884 0)
			(effects
				(font
					(size 1.27 1.27)
				)
				(justify left bottom)
			)
		)
		(property "Sheetfile" "supply.kicad_sch"
			(at 171.45 241.8846 0)
			(effects
				(font
					(size 1.27 1.27)
				)
				(justify left top)
			)
		)
		(instances
			(project "jetson-orin-baseboard"
				(path ""
					(page "10")
				)
			)
		)
	)
	(sheet
		(at 76.2 203.2)
		(size 12.7 12.7)
		(fields_autoplaced yes)
		(stroke
			(width 0.1524)
			(type solid)
		)
		(fill
			(color 0 0 0 0.0000)
		)
		(property "Sheetname" "SoM"
			(at 76.2 202.4884 0)
			(effects
				(font
					(size 1.27 1.27)
				)
				(justify left bottom)
			)
		)
		(property "Sheetfile" "som.kicad_sch"
			(at 76.2 216.4846 0)
			(effects
				(font
					(size 1.27 1.27)
				)
				(justify left top)
			)
		)
		(instances
			(project "jetson-orin-baseboard"
				(path ""
					(page "2")
				)
			)
		)
	)
	(sheet
		(at 107.95 228.6)
		(size 12.7 12.7)
		(fields_autoplaced yes)
		(stroke
			(width 0.1524)
			(type solid)
		)
		(fill
			(color 0 0 0 0.0000)
		)
		(property "Sheetname" "CSI"
			(at 107.95 227.8884 0)
			(effects
				(font
					(size 1.27 1.27)
				)
				(justify left bottom)
			)
		)
		(property "Sheetfile" "csi.kicad_sch"
			(at 107.95 241.8846 0)
			(effects
				(font
					(size 1.27 1.27)
				)
				(justify left top)
			)
		)
		(instances
			(project "jetson-orin-baseboard"
				(path ""
					(page "8")
				)
			)
		)
	)
	(sheet
		(at 107.95 203.2)
		(size 12.7 12.7)
		(fields_autoplaced yes)
		(stroke
			(width 0.1524)
			(type solid)
		)
		(fill
			(color 0 0 0 0.0000)
		)
		(property "Sheetname" "M.2"
			(at 107.95 202.4884 0)
			(effects
				(font
					(size 1.27 1.27)
				)
				(justify left bottom)
			)
		)
		(property "Sheetfile" "m-2.kicad_sch"
			(at 107.95 216.4846 0)
			(effects
				(font
					(size 1.27 1.27)
				)
				(justify left top)
			)
		)
		(instances
			(project "jetson-orin-baseboard"
				(path ""
					(page "3")
				)
			)
		)
	)
	(sheet
		(at 76.2 228.6)
		(size 12.7 12.7)
		(fields_autoplaced yes)
		(stroke
			(width 0.1524)
			(type solid)
		)
		(fill
			(color 0 0 0 0.0000)
		)
		(property "Sheetname" "Ethernet"
			(at 76.2 227.8884 0)
			(effects
				(font
					(size 1.27 1.27)
				)
				(justify left bottom)
			)
		)
		(property "Sheetfile" "ethernet.kicad_sch"
			(at 76.2 241.8846 0)
			(effects
				(font
					(size 1.27 1.27)
				)
				(justify left top)
			)
		)
		(instances
			(project "jetson-orin-baseboard"
				(path ""
					(page "7")
				)
			)
		)
	)
	(sheet
		(at 139.7 228.6)
		(size 12.7 12.7)
		(fields_autoplaced yes)
		(stroke
			(width 0.1524)
			(type solid)
		)
		(fill
			(color 0 0 0 0.0000)
		)
		(property "Sheetname" "Peripherals"
			(at 139.7 227.8884 0)
			(effects
				(font
					(size 1.27 1.27)
				)
				(justify left bottom)
			)
		)
		(property "Sheetfile" "peripherals.kicad_sch"
			(at 139.7 241.8846 0)
			(effects
				(font
					(size 1.27 1.27)
				)
				(justify left top)
			)
		)
		(instances
			(project "jetson-orin-baseboard"
				(path ""
					(page "9")
				)
			)
		)
	)
	(sheet
		(at 139.7 203.2)
		(size 12.7 12.7)
		(fields_autoplaced yes)
		(stroke
			(width 0.1524)
			(type solid)
		)
		(fill
			(color 0 0 0 0.0000)
		)
		(property "Sheetname" "USB Debug, DP"
			(at 139.7 202.4884 0)
			(effects
				(font
					(size 1.27 1.27)
				)
				(justify left bottom)
			)
		)
		(property "Sheetfile" "usb.kicad_sch"
			(at 139.7 216.4846 0)
			(effects
				(font
					(size 1.27 1.27)
				)
				(justify left top)
			)
		)
		(instances
			(project "jetson-orin-baseboard"
				(path ""
					(page "4")
				)
			)
		)
	)
	(sheet_instances
		(path "/"
			(page "1")
		)
	)
)
